(kicad_pcb
	(version 20260206)
	(generator "pcbnew")
	(generator_version "10.0")
	(general
		(thickness 1.6)
		(legacy_teardrops no)
	)
	(paper "A4")
	(title_block
		(title "01162023_DA0F0TEBIF0_F0T_Expander_BD_F_brd_V02_OCP.brd")
		(comment 1 "Grand Teton / footprints 7565-7572 of 9728")
	)
	(layers
		(0 "F.Cu" signal "TOP")
		(4 "In1.Cu" signal "GND")
		(6 "In2.Cu" signal "VCC")
		(8 "In3.Cu" signal "VCC1")
		(10 "In4.Cu" signal "GND1")
		(12 "In5.Cu" signal "IN1")
		(14 "In6.Cu" signal "GND2")
		(16 "In7.Cu" signal "IN2")
		(18 "In8.Cu" signal "GND3")
		(20 "In9.Cu" signal "IN3")
		(22 "In10.Cu" signal "GND4")
		(24 "In11.Cu" signal "IN4")
		(26 "In12.Cu" signal "GND5")
		(28 "In13.Cu" signal "IN5")
		(30 "In14.Cu" signal "GND6")
		(32 "In15.Cu" signal "IN6")
		(34 "In16.Cu" signal "GND7")
		(2 "B.Cu" signal "BOTTOM")
		(9 "F.Adhes" user "F.Adhesive")
		(11 "B.Adhes" user "B.Adhesive")
		(13 "F.Paste" user "Package Geometry/Pastemask Top")
		(15 "B.Paste" user "Package Geometry/Pastemask Bottom")
		(5 "F.SilkS" user "Ref Des/Silkscreen Top")
		(7 "B.SilkS" user "Ref Des/Silkscreen Bottom")
		(1 "F.Mask" user "Board Geometry/Soldermask Top")
		(3 "B.Mask" user "Board Geometry/Soldermask Bottom")
		(17 "Dwgs.User" user "User.Drawings")
		(19 "Cmts.User" user "User.Comments")
		(21 "Eco1.User" user "User.Eco1")
		(23 "Eco2.User" user "User.Eco2")
		(25 "Edge.Cuts" user "Board Geometry/Outline")
		(27 "Margin" user)
		(31 "F.CrtYd" user "Package Geometry/Place Bound Top")
		(29 "B.CrtYd" user "Package Geometry/Place Bound Bottom")
		(35 "F.Fab" user "Ref Des/Assembly Top")
		(33 "B.Fab" user "Ref Des/Assembly Bottom")
	)
	(footprint ""
		(layer "B.Cu")
		(at 289.47491 -297.79976 90)
		(property "Reference" "C1661"
			(at 0 0 90)
			(layer "B.SilkS")
			(hide yes)
			(effects
				(font
					(size 1.27 1.27)
				)
				(justify mirror)
			)
		)
		(property "Value" ""
			(at 0 0 90)
			(layer "B.Fab")
			(effects
				(font
					(size 1.27 1.27)
				)
				(justify mirror)
			)
		)
		(duplicate_pad_numbers_are_jumpers no)
		(fp_line
			(start 0.299974 -0.150114)
			(end -0.299974 -0.150114)
			(stroke
				(width 0.1)
				(type default)
			)
			(layer "B.Fab")
		)
		(fp_line
			(start -0.299974 -0.150114)
			(end -0.299974 0.150114)
			(stroke
				(width 0.1)
				(type default)
			)
			(layer "B.Fab")
		)
		(fp_line
			(start 0.299974 0.150114)
			(end 0.299974 -0.150114)
			(stroke
				(width 0.1)
				(type default)
			)
			(layer "B.Fab")
		)
		(fp_line
			(start -0.299974 0.150114)
			(end 0.299974 0.150114)
			(stroke
				(width 0.1)
				(type default)
			)
			(layer "B.Fab")
		)
		(pad "1" smd rect
			(at 0.2667 0 270)
			(size 0.3048 0.381)
			(layers "B.Cu" "B.Mask" "B.Paste")
			(net "P0V8_PEX2")
		)
		(pad "2" smd rect
			(at -0.2667 0 270)
			(size 0.3048 0.381)
			(layers "B.Cu" "B.Mask" "B.Paste")
			(net "GND")
		)
	)
	(footprint ""
		(layer "B.Cu")
		(at 230.747316 -212.56625 180)
		(property "Reference" "C2027"
			(at 0 0 0)
			(layer "B.SilkS")
			(hide yes)
			(effects
				(font
					(size 1.27 1.27)
				)
				(justify mirror)
			)
		)
		(property "Value" ""
			(at 0 0 0)
			(layer "B.Fab")
			(effects
				(font
					(size 1.27 1.27)
				)
				(justify mirror)
			)
		)
		(duplicate_pad_numbers_are_jumpers no)
		(fp_line
			(start 0.69215 0.2921)
			(end 0.69215 -0.2921)
			(stroke
				(width 0.1524)
				(type default)
			)
			(layer "B.SilkS")
		)
		(fp_line
			(start 0.69215 -0.2921)
			(end -0.69215 -0.2921)
			(stroke
				(width 0.1524)
				(type default)
			)
			(layer "B.SilkS")
		)
		(fp_line
			(start -0.69215 0.2921)
			(end 0.69215 0.2921)
			(stroke
				(width 0.1524)
				(type default)
			)
			(layer "B.SilkS")
		)
		(fp_line
			(start -0.69215 -0.2921)
			(end -0.69215 0.2921)
			(stroke
				(width 0.1524)
				(type default)
			)
			(layer "B.SilkS")
		)
		(fp_line
			(start 0.51435 0.2794)
			(end 0.51435 -0.2794)
			(stroke
				(width 0.1)
				(type default)
			)
			(layer "B.Fab")
		)
		(fp_line
			(start 0.51435 -0.2794)
			(end -0.51435 -0.2794)
			(stroke
				(width 0.1)
				(type default)
			)
			(layer "B.Fab")
		)
		(fp_line
			(start -0.51435 0.2794)
			(end 0.51435 0.2794)
			(stroke
				(width 0.1)
				(type default)
			)
			(layer "B.Fab")
		)
		(fp_line
			(start -0.51435 -0.2794)
			(end -0.51435 0.2794)
			(stroke
				(width 0.1)
				(type default)
			)
			(layer "B.Fab")
		)
		(pad "1" smd circle
			(at 0.40005 0)
			(size 0 0)
			(layers "B.Cu" "B.Mask" "B.Paste")
			(net "P3V3_BIC_SPI")
		)
		(pad "2" smd circle
			(at -0.40005 0)
			(size 0 0)
			(layers "B.Cu" "B.Mask" "B.Paste")
			(net "GND")
		)
		(zone
			(layer "B.Cu")
			(hatch none 0.5)
			(connect_pads
				(clearance 0)
			)
			(min_thickness 0.25)
			(keepout
				(tracks not_allowed)
				(vias allowed)
				(pads allowed)
				(copperpour not_allowed)
				(footprints allowed)
			)
			(placement
				(enabled no)
				(sheetname "")
			)
			(fill
				(thermal_gap 0.5)
				(thermal_bridge_width 0.5)
				(island_removal_mode 0)
			)
			(polygon
				(pts
					(xy 230.556816 -212.65388) (xy 230.648256 -212.712046) (xy 230.847646 -212.712046) (xy 230.937816 -212.65388)
					(xy 230.937816 -212.47862) (xy 230.847646 -212.4202) (xy 230.648256 -212.4202) (xy 230.556816 -212.478366)
				)
			)
		)
	)
	(footprint ""
		(layer "B.Cu")
		(at 48.866044 -138.421618 180)
		(property "Reference" "R3"
			(at 0 0 0)
			(layer "B.SilkS")
			(hide yes)
			(effects
				(font
					(size 1.27 1.27)
				)
				(justify mirror)
			)
		)
		(property "Value" ""
			(at 0 0 0)
			(layer "B.Fab")
			(effects
				(font
					(size 1.27 1.27)
				)
				(justify mirror)
			)
		)
		(duplicate_pad_numbers_are_jumpers no)
		(fp_line
			(start 0.7874 0.4064)
			(end 0.7874 -0.4064)
			(stroke
				(width 0.1524)
				(type default)
			)
			(layer "B.SilkS")
		)
		(fp_line
			(start 0.7874 -0.4064)
			(end -0.7874 -0.4064)
			(stroke
				(width 0.1524)
				(type default)
			)
			(layer "B.SilkS")
		)
		(fp_line
			(start -0.7874 0.4064)
			(end 0.7874 0.4064)
			(stroke
				(width 0.1524)
				(type default)
			)
			(layer "B.SilkS")
		)
		(fp_line
			(start -0.7874 -0.4064)
			(end -0.7874 0.4064)
			(stroke
				(width 0.1524)
				(type default)
			)
			(layer "B.SilkS")
		)
		(fp_line
			(start 0.67945 0.3048)
			(end 0.67945 -0.305054)
			(stroke
				(width 0.1)
				(type default)
			)
			(layer "B.Fab")
		)
		(fp_line
			(start 0.67945 -0.305054)
			(end 0.12065 -0.305054)
			(stroke
				(width 0.1)
				(type default)
			)
			(layer "B.Fab")
		)
		(fp_line
			(start 0.12065 0.3048)
			(end 0.67945 0.3048)
			(stroke
				(width 0.1)
				(type default)
			)
			(layer "B.Fab")
		)
		(fp_line
			(start 0.12065 0.2794)
			(end 0.12065 0.3048)
			(stroke
				(width 0.1)
				(type default)
			)
			(layer "B.Fab")
		)
		(fp_line
			(start 0.12065 -0.2794)
			(end -0.12065 -0.2794)
			(stroke
				(width 0.1)
				(type default)
			)
			(layer "B.Fab")
		)
		(fp_line
			(start 0.12065 -0.305054)
			(end 0.12065 -0.2794)
			(stroke
				(width 0.1)
				(type default)
			)
			(layer "B.Fab")
		)
		(fp_line
			(start -0.120396 0.3048)
			(end -0.120396 0.2794)
			(stroke
				(width 0.1)
				(type default)
			)
			(layer "B.Fab")
		)
		(fp_line
			(start -0.120396 0.2794)
			(end 0.12065 0.2794)
			(stroke
				(width 0.1)
				(type default)
			)
			(layer "B.Fab")
		)
		(fp_line
			(start -0.12065 -0.2794)
			(end -0.12065 -0.3048)
			(stroke
				(width 0.1)
				(type default)
			)
			(layer "B.Fab")
		)
		(fp_line
			(start -0.12065 -0.3048)
			(end -0.67945 -0.3048)
			(stroke
				(width 0.1)
				(type default)
			)
			(layer "B.Fab")
		)
		(fp_line
			(start -0.67945 0.3048)
			(end -0.120396 0.3048)
			(stroke
				(width 0.1)
				(type default)
			)
			(layer "B.Fab")
		)
		(fp_line
			(start -0.67945 -0.3048)
			(end -0.67945 0.3048)
			(stroke
				(width 0.1)
				(type default)
			)
			(layer "B.Fab")
		)
		(pad "1" smd circle
			(at 0.40005 0)
			(size 0 0)
			(layers "B.Cu" "B.Mask" "B.Paste")
			(net "NIC0_AUX_PWR_EN_R")
		)
		(pad "2" smd circle
			(at -0.40005 0)
			(size 0 0)
			(layers "B.Cu" "B.Mask" "B.Paste")
			(net "NIC0_AUX_PWR_EN")
		)
	)
	(footprint ""
		(layer "B.Cu")
		(at 309.741824 -103.104696 180)
		(property "Reference" "R271"
			(at 0 0 0)
			(layer "B.SilkS")
			(hide yes)
			(effects
				(font
					(size 1.27 1.27)
				)
				(justify mirror)
			)
		)
		(property "Value" ""
			(at 0 0 0)
			(layer "B.Fab")
			(effects
				(font
					(size 1.27 1.27)
				)
				(justify mirror)
			)
		)
		(duplicate_pad_numbers_are_jumpers no)
		(fp_line
			(start 0.7874 0.4064)
			(end 0.7874 -0.4064)
			(stroke
				(width 0.1524)
				(type default)
			)
			(layer "B.SilkS")
		)
		(fp_line
			(start 0.7874 -0.4064)
			(end -0.7874 -0.4064)
			(stroke
				(width 0.1524)
				(type default)
			)
			(layer "B.SilkS")
		)
		(fp_line
			(start -0.7874 0.4064)
			(end 0.7874 0.4064)
			(stroke
				(width 0.1524)
				(type default)
			)
			(layer "B.SilkS")
		)
		(fp_line
			(start -0.7874 -0.4064)
			(end -0.7874 0.4064)
			(stroke
				(width 0.1524)
				(type default)
			)
			(layer "B.SilkS")
		)
		(fp_line
			(start 0.67945 0.3048)
			(end 0.67945 -0.305054)
			(stroke
				(width 0.1)
				(type default)
			)
			(layer "B.Fab")
		)
		(fp_line
			(start 0.67945 -0.305054)
			(end 0.12065 -0.305054)
			(stroke
				(width 0.1)
				(type default)
			)
			(layer "B.Fab")
		)
		(fp_line
			(start 0.12065 0.3048)
			(end 0.67945 0.3048)
			(stroke
				(width 0.1)
				(type default)
			)
			(layer "B.Fab")
		)
		(fp_line
			(start 0.12065 0.2794)
			(end 0.12065 0.3048)
			(stroke
				(width 0.1)
				(type default)
			)
			(layer "B.Fab")
		)
		(fp_line
			(start 0.12065 -0.2794)
			(end -0.12065 -0.2794)
			(stroke
				(width 0.1)
				(type default)
			)
			(layer "B.Fab")
		)
		(fp_line
			(start 0.12065 -0.305054)
			(end 0.12065 -0.2794)
			(stroke
				(width 0.1)
				(type default)
			)
			(layer "B.Fab")
		)
		(fp_line
			(start -0.120396 0.3048)
			(end -0.120396 0.2794)
			(stroke
				(width 0.1)
				(type default)
			)
			(layer "B.Fab")
		)
		(fp_line
			(start -0.120396 0.2794)
			(end 0.12065 0.2794)
			(stroke
				(width 0.1)
				(type default)
			)
			(layer "B.Fab")
		)
		(fp_line
			(start -0.12065 -0.2794)
			(end -0.12065 -0.3048)
			(stroke
				(width 0.1)
				(type default)
			)
			(layer "B.Fab")
		)
		(fp_line
			(start -0.12065 -0.3048)
			(end -0.67945 -0.3048)
			(stroke
				(width 0.1)
				(type default)
			)
			(layer "B.Fab")
		)
		(fp_line
			(start -0.67945 0.3048)
			(end -0.120396 0.3048)
			(stroke
				(width 0.1)
				(type default)
			)
			(layer "B.Fab")
		)
		(fp_line
			(start -0.67945 -0.3048)
			(end -0.67945 0.3048)
			(stroke
				(width 0.1)
				(type default)
			)
			(layer "B.Fab")
		)
		(pad "1" smd circle
			(at 0.40005 0)
			(size 0 0)
			(layers "B.Cu" "B.Mask" "B.Paste")
			(net "NCSI_NIC5_RXD0")
		)
		(pad "2" smd circle
			(at -0.40005 0)
			(size 0 0)
			(layers "B.Cu" "B.Mask" "B.Paste")
			(net "GND")
		)
	)
	(footprint ""
		(layer "B.Cu")
		(at 397.02486 -293.99992 90)
		(property "Reference" "C1891"
			(at 0 0 90)
			(layer "B.SilkS")
			(hide yes)
			(effects
				(font
					(size 1.27 1.27)
				)
				(justify mirror)
			)
		)
		(property "Value" ""
			(at 0 0 90)
			(layer "B.Fab")
			(effects
				(font
					(size 1.27 1.27)
				)
				(justify mirror)
			)
		)
		(duplicate_pad_numbers_are_jumpers no)
		(fp_line
			(start 0.299974 -0.150114)
			(end -0.299974 -0.150114)
			(stroke
				(width 0.1)
				(type default)
			)
			(layer "B.Fab")
		)
		(fp_line
			(start -0.299974 -0.150114)
			(end -0.299974 0.150114)
			(stroke
				(width 0.1)
				(type default)
			)
			(layer "B.Fab")
		)
		(fp_line
			(start 0.299974 0.150114)
			(end 0.299974 -0.150114)
			(stroke
				(width 0.1)
				(type default)
			)
			(layer "B.Fab")
		)
		(fp_line
			(start -0.299974 0.150114)
			(end 0.299974 0.150114)
			(stroke
				(width 0.1)
				(type default)
			)
			(layer "B.Fab")
		)
		(pad "1" smd rect
			(at 0.2667 0 270)
			(size 0.3048 0.381)
			(layers "B.Cu" "B.Mask" "B.Paste")
			(net "P0V8_PEX3")
		)
		(pad "2" smd rect
			(at -0.2667 0 270)
			(size 0.3048 0.381)
			(layers "B.Cu" "B.Mask" "B.Paste")
			(net "GND")
		)
	)
	(footprint ""
		(layer "B.Cu")
		(at 283.774896 -293.99992 -90)
		(property "Reference" "C1666"
			(at 0 0 90)
			(layer "B.SilkS")
			(hide yes)
			(effects
				(font
					(size 1.27 1.27)
				)
				(justify mirror)
			)
		)
		(property "Value" ""
			(at 0 0 90)
			(layer "B.Fab")
			(effects
				(font
					(size 1.27 1.27)
				)
				(justify mirror)
			)
		)
		(duplicate_pad_numbers_are_jumpers no)
		(fp_line
			(start -0.299974 0.150114)
			(end 0.299974 0.150114)
			(stroke
				(width 0.1)
				(type default)
			)
			(layer "B.Fab")
		)
		(fp_line
			(start 0.299974 0.150114)
			(end 0.299974 -0.150114)
			(stroke
				(width 0.1)
				(type default)
			)
			(layer "B.Fab")
		)
		(fp_line
			(start -0.299974 -0.150114)
			(end -0.299974 0.150114)
			(stroke
				(width 0.1)
				(type default)
			)
			(layer "B.Fab")
		)
		(fp_line
			(start 0.299974 -0.150114)
			(end -0.299974 -0.150114)
			(stroke
				(width 0.1)
				(type default)
			)
			(layer "B.Fab")
		)
		(pad "1" smd rect
			(at 0.2667 0 90)
			(size 0.3048 0.381)
			(layers "B.Cu" "B.Mask" "B.Paste")
			(net "P0V8_PEX2")
		)
		(pad "2" smd rect
			(at -0.2667 0 90)
			(size 0.3048 0.381)
			(layers "B.Cu" "B.Mask" "B.Paste")
			(net "GND")
		)
	)
	(footprint ""
		(layer "B.Cu")
		(at 180.50002 -290.199826 90)
		(property "Reference" "C1465"
			(at 0 0 90)
			(layer "B.SilkS")
			(hide yes)
			(effects
				(font
					(size 1.27 1.27)
				)
				(justify mirror)
			)
		)
		(property "Value" ""
			(at 0 0 90)
			(layer "B.Fab")
			(effects
				(font
					(size 1.27 1.27)
				)
				(justify mirror)
			)
		)
		(duplicate_pad_numbers_are_jumpers no)
		(fp_line
			(start 0.299974 -0.150114)
			(end -0.299974 -0.150114)
			(stroke
				(width 0.1)
				(type default)
			)
			(layer "B.Fab")
		)
		(fp_line
			(start -0.299974 -0.150114)
			(end -0.299974 0.150114)
			(stroke
				(width 0.1)
				(type default)
			)
			(layer "B.Fab")
		)
		(fp_line
			(start 0.299974 0.150114)
			(end 0.299974 -0.150114)
			(stroke
				(width 0.1)
				(type default)
			)
			(layer "B.Fab")
		)
		(fp_line
			(start -0.299974 0.150114)
			(end 0.299974 0.150114)
			(stroke
				(width 0.1)
				(type default)
			)
			(layer "B.Fab")
		)
		(pad "1" smd rect
			(at 0.2667 0 270)
			(size 0.3048 0.381)
			(layers "B.Cu" "B.Mask" "B.Paste")
			(net "P0V8_SERDES_VDDA_PEX1")
		)
		(pad "2" smd rect
			(at -0.2667 0 270)
			(size 0.3048 0.381)
			(layers "B.Cu" "B.Mask" "B.Paste")
			(net "GND")
		)
	)
	(footprint ""
		(layer "B.Cu")
		(at 416.972242 -112.421924)
		(property "Reference" "R366"
			(at 0 0 0)
			(layer "B.SilkS")
			(hide yes)
			(effects
				(font
					(size 1.27 1.27)
				)
				(justify mirror)
			)
		)
		(property "Value" ""
			(at 0 0 0)
			(layer "B.Fab")
			(effects
				(font
					(size 1.27 1.27)
				)
				(justify mirror)
			)
		)
		(duplicate_pad_numbers_are_jumpers no)
		(fp_line
			(start -0.7874 -0.4064)
			(end -0.7874 0.4064)
			(stroke
				(width 0.1524)
				(type default)
			)
			(layer "B.SilkS")
		)
		(fp_line
			(start -0.7874 0.4064)
			(end 0.7874 0.4064)
			(stroke
				(width 0.1524)
				(type default)
			)
			(layer "B.SilkS")
		)
		(fp_line
			(start 0.7874 -0.4064)
			(end -0.7874 -0.4064)
			(stroke
				(width 0.1524)
				(type default)
			)
			(layer "B.SilkS")
		)
		(fp_line
			(start 0.7874 0.4064)
			(end 0.7874 -0.4064)
			(stroke
				(width 0.1524)
				(type default)
			)
			(layer "B.SilkS")
		)
		(fp_line
			(start -0.67945 -0.3048)
			(end -0.67945 0.3048)
			(stroke
				(width 0.1)
				(type default)
			)
			(layer "B.Fab")
		)
		(fp_line
			(start -0.67945 0.3048)
			(end -0.120396 0.3048)
			(stroke
				(width 0.1)
				(type default)
			)
			(layer "B.Fab")
		)
		(fp_line
			(start -0.12065 -0.3048)
			(end -0.67945 -0.3048)
			(stroke
				(width 0.1)
				(type default)
			)
			(layer "B.Fab")
		)
		(fp_line
			(start -0.12065 -0.2794)
			(end -0.12065 -0.3048)
			(stroke
				(width 0.1)
				(type default)
			)
			(layer "B.Fab")
		)
		(fp_line
			(start -0.120396 0.2794)
			(end 0.12065 0.2794)
			(stroke
				(width 0.1)
				(type default)
			)
			(layer "B.Fab")
		)
		(fp_line
			(start -0.120396 0.3048)
			(end -0.120396 0.2794)
			(stroke
				(width 0.1)
				(type default)
			)
			(layer "B.Fab")
		)
		(fp_line
			(start 0.12065 -0.305054)
			(end 0.12065 -0.2794)
			(stroke
				(width 0.1)
				(type default)
			)
			(layer "B.Fab")
		)
		(fp_line
			(start 0.12065 -0.2794)
			(end -0.12065 -0.2794)
			(stroke
				(width 0.1)
				(type default)
			)
			(layer "B.Fab")
		)
		(fp_line
			(start 0.12065 0.2794)
			(end 0.12065 0.3048)
			(stroke
				(width 0.1)
				(type default)
			)
			(layer "B.Fab")
		)
		(fp_line
			(start 0.12065 0.3048)
			(end 0.67945 0.3048)
			(stroke
				(width 0.1)
				(type default)
			)
			(layer "B.Fab")
		)
		(fp_line
			(start 0.67945 -0.305054)
			(end 0.12065 -0.305054)
			(stroke
				(width 0.1)
				(type default)
			)
			(layer "B.Fab")
		)
		(fp_line
			(start 0.67945 0.3048)
			(end 0.67945 -0.305054)
			(stroke
				(width 0.1)
				(type default)
			)
			(layer "B.Fab")
		)
		(pad "1" smd circle
			(at 0.40005 0 180)
			(size 0 0)
			(layers "B.Cu" "B.Mask" "B.Paste")
			(net "P3V3_NIC7")
		)
		(pad "2" smd circle
			(at -0.40005 0 180)
			(size 0 0)
			(layers "B.Cu" "B.Mask" "B.Paste")
			(net "SMB_NIC7_LS_SCL")
		)
	)
)
